(kicad_sch
	(version 20250114)
	(generator "eeschema")
	(generator_version "9.0")
	(paper "A3")
	(title_block
		(title "RDIMM DDR5 Tester")
		(date "2026-05-21")
		(rev "2.2.0")
		(company "Antmicro")
		(comment 1 "www.antmicro.com")
		(comment 2 "Antmicro")
	)
	(text "PCIe"
		(exclude_from_sim no)
		(at 16.51 22.86 0)
		(effects
			(font
				(size 3 3)
				(thickness 0.6)
				(bold yes)
			)
			(justify left bottom)
		)
	)
	(junction
		(at 182.88 213.36)
		(diameter 0)
		(color 0 0 0 0)
	)
	(junction
		(at 179.07 68.58)
		(diameter 0)
		(color 0 0 0 0)
	)
	(junction
		(at 219.71 210.82)
		(diameter 0)
		(color 0 0 0 0)
	)
	(junction
		(at 182.88 210.82)
		(diameter 0)
		(color 0 0 0 0)
	)
	(junction
		(at 165.1 68.58)
		(diameter 0)
		(color 0 0 0 0)
	)
	(no_connect
		(at 193.04 73.66)
	)
	(no_connect
		(at 193.04 96.52)
	)
	(no_connect
		(at 226.06 109.22)
	)
	(no_connect
		(at 226.06 99.06)
	)
	(no_connect
		(at 193.04 88.9)
	)
	(no_connect
		(at 226.06 91.44)
	)
	(no_connect
		(at 226.06 93.98)
	)
	(no_connect
		(at 226.06 111.76)
	)
	(no_connect
		(at 193.04 91.44)
	)
	(no_connect
		(at 226.06 88.9)
	)
	(no_connect
		(at 193.04 93.98)
	)
	(no_connect
		(at 193.04 71.12)
	)
	(bus_entry
		(at 245.11 127)
		(size 2.54 -2.54)
		(stroke
			(width 0)
			(type default)
		)
	)
	(bus_entry
		(at 245.11 172.72)
		(size 2.54 -2.54)
		(stroke
			(width 0)
			(type default)
		)
	)
	(bus_entry
		(at 245.11 134.62)
		(size 2.54 -2.54)
		(stroke
			(width 0)
			(type default)
		)
	)
	(bus_entry
		(at 245.11 147.32)
		(size 2.54 -2.54)
		(stroke
			(width 0)
			(type default)
		)
	)
	(bus_entry
		(at 245.11 142.24)
		(size 2.54 -2.54)
		(stroke
			(width 0)
			(type default)
		)
	)
	(bus_entry
		(at 245.11 116.84)
		(size 2.54 -2.54)
		(stroke
			(width 0)
			(type default)
		)
	)
	(bus_entry
		(at 167.64 132.08)
		(size -2.54 -2.54)
		(stroke
			(width 0)
			(type default)
		)
	)
	(bus_entry
		(at 245.11 149.86)
		(size 2.54 -2.54)
		(stroke
			(width 0)
			(type default)
		)
	)
	(bus_entry
		(at 245.11 119.38)
		(size 2.54 -2.54)
		(stroke
			(width 0)
			(type default)
		)
	)
	(bus_entry
		(at 245.11 165.1)
		(size 2.54 -2.54)
		(stroke
			(width 0)
			(type default)
		)
	)
	(bus_entry
		(at 245.11 139.7)
		(size 2.54 -2.54)
		(stroke
			(width 0)
			(type default)
		)
	)
	(bus_entry
		(at 167.64 162.56)
		(size -2.54 -2.54)
		(stroke
			(width 0)
			(type default)
		)
	)
	(bus_entry
		(at 245.11 157.48)
		(size 2.54 -2.54)
		(stroke
			(width 0)
			(type default)
		)
	)
	(bus_entry
		(at 245.11 124.46)
		(size 2.54 -2.54)
		(stroke
			(width 0)
			(type default)
		)
	)
	(bus_entry
		(at 167.64 172.72)
		(size -2.54 -2.54)
		(stroke
			(width 0)
			(type default)
		)
	)
	(bus_entry
		(at 167.64 119.38)
		(size -2.54 -2.54)
		(stroke
			(width 0)
			(type default)
		)
	)
	(bus_entry
		(at 167.64 139.7)
		(size -2.54 -2.54)
		(stroke
			(width 0)
			(type default)
		)
	)
	(bus_entry
		(at 167.64 149.86)
		(size -2.54 -2.54)
		(stroke
			(width 0)
			(type default)
		)
	)
	(bus_entry
		(at 167.64 111.76)
		(size -2.54 -2.54)
		(stroke
			(width 0)
			(type default)
		)
	)
	(bus_entry
		(at 245.11 170.18)
		(size 2.54 -2.54)
		(stroke
			(width 0)
			(type default)
		)
	)
	(bus_entry
		(at 167.64 157.48)
		(size -2.54 -2.54)
		(stroke
			(width 0)
			(type default)
		)
	)
	(bus_entry
		(at 245.11 132.08)
		(size 2.54 -2.54)
		(stroke
			(width 0)
			(type default)
		)
	)
	(bus_entry
		(at 245.11 154.94)
		(size 2.54 -2.54)
		(stroke
			(width 0)
			(type default)
		)
	)
	(bus_entry
		(at 167.64 109.22)
		(size -2.54 -2.54)
		(stroke
			(width 0)
			(type default)
		)
	)
	(bus_entry
		(at 245.11 162.56)
		(size 2.54 -2.54)
		(stroke
			(width 0)
			(type default)
		)
	)
	(bus_entry
		(at 167.64 134.62)
		(size -2.54 -2.54)
		(stroke
			(width 0)
			(type default)
		)
	)
	(bus_entry
		(at 167.64 124.46)
		(size -2.54 -2.54)
		(stroke
			(width 0)
			(type default)
		)
	)
	(bus_entry
		(at 167.64 142.24)
		(size -2.54 -2.54)
		(stroke
			(width 0)
			(type default)
		)
	)
	(bus_entry
		(at 167.64 154.94)
		(size -2.54 -2.54)
		(stroke
			(width 0)
			(type default)
		)
	)
	(bus_entry
		(at 167.64 165.1)
		(size -2.54 -2.54)
		(stroke
			(width 0)
			(type default)
		)
	)
	(bus_entry
		(at 167.64 116.84)
		(size -2.54 -2.54)
		(stroke
			(width 0)
			(type default)
		)
	)
	(bus_entry
		(at 167.64 170.18)
		(size -2.54 -2.54)
		(stroke
			(width 0)
			(type default)
		)
	)
	(bus_entry
		(at 167.64 147.32)
		(size -2.54 -2.54)
		(stroke
			(width 0)
			(type default)
		)
	)
	(bus_entry
		(at 167.64 127)
		(size -2.54 -2.54)
		(stroke
			(width 0)
			(type default)
		)
	)
	(bus
		(pts
			(xy 165.1 129.54) (xy 165.1 132.08)
		)
		(stroke
			(width 0)
			(type default)
		)
	)
	(wire
		(pts
			(xy 165.1 68.58) (xy 179.07 68.58)
		)
		(stroke
			(width 0)
			(type default)
		)
	)
	(wire
		(pts
			(xy 167.64 111.76) (xy 193.04 111.76)
		)
		(stroke
			(width 0)
			(type default)
		)
	)
	(wire
		(pts
			(xy 219.71 208.28) (xy 219.71 210.82)
		)
		(stroke
			(width 0)
			(type default)
		)
	)
	(wire
		(pts
			(xy 245.11 170.18) (xy 226.06 170.18)
		)
		(stroke
			(width 0)
			(type default)
		)
	)
	(bus
		(pts
			(xy 247.65 139.7) (xy 247.65 144.78)
		)
		(stroke
			(width 0)
			(type default)
		)
	)
	(wire
		(pts
			(xy 198.12 215.9) (xy 204.47 215.9)
		)
		(stroke
			(width 0)
			(type default)
		)
	)
	(bus
		(pts
			(xy 165.1 167.64) (xy 165.1 170.18)
		)
		(stroke
			(width 0)
			(type default)
		)
	)
	(wire
		(pts
			(xy 245.11 154.94) (xy 226.06 154.94)
		)
		(stroke
			(width 0)
			(type default)
		)
	)
	(wire
		(pts
			(xy 179.07 68.58) (xy 193.04 68.58)
		)
		(stroke
			(width 0)
			(type default)
		)
	)
	(wire
		(pts
			(xy 226.06 71.12) (xy 236.22 71.12)
		)
		(stroke
			(width 0)
			(type default)
		)
	)
	(wire
		(pts
			(xy 193.04 132.08) (xy 167.64 132.08)
		)
		(stroke
			(width 0)
			(type default)
		)
	)
	(wire
		(pts
			(xy 226.06 76.2) (xy 236.22 76.2)
		)
		(stroke
			(width 0)
			(type default)
		)
	)
	(wire
		(pts
			(xy 219.71 210.82) (xy 219.71 212.09)
		)
		(stroke
			(width 0)
			(type default)
		)
	)
	(bus
		(pts
			(xy 247.65 121.92) (xy 247.65 124.46)
		)
		(stroke
			(width 0)
			(type default)
		)
	)
	(bus
		(pts
			(xy 165.1 160.02) (xy 165.1 162.56)
		)
		(stroke
			(width 0)
			(type default)
		)
	)
	(bus
		(pts
			(xy 247.65 137.16) (xy 247.65 139.7)
		)
		(stroke
			(width 0)
			(type default)
		)
	)
	(wire
		(pts
			(xy 245.11 147.32) (xy 226.06 147.32)
		)
		(stroke
			(width 0)
			(type default)
		)
	)
	(wire
		(pts
			(xy 245.11 149.86) (xy 226.06 149.86)
		)
		(stroke
			(width 0)
			(type default)
		)
	)
	(wire
		(pts
			(xy 245.11 119.38) (xy 226.06 119.38)
		)
		(stroke
			(width 0)
			(type default)
		)
	)
	(wire
		(pts
			(xy 182.88 210.82) (xy 185.42 210.82)
		)
		(stroke
			(width 0)
			(type default)
		)
	)
	(wire
		(pts
			(xy 245.11 124.46) (xy 226.06 124.46)
		)
		(stroke
			(width 0)
			(type default)
		)
	)
	(wire
		(pts
			(xy 193.04 134.62) (xy 167.64 134.62)
		)
		(stroke
			(width 0)
			(type default)
		)
	)
	(bus
		(pts
			(xy 247.65 160.02) (xy 247.65 162.56)
		)
		(stroke
			(width 0)
			(type default)
		)
	)
	(wire
		(pts
			(xy 182.88 210.82) (xy 182.88 213.36)
		)
		(stroke
			(width 0)
			(type default)
		)
	)
	(wire
		(pts
			(xy 193.04 139.7) (xy 167.64 139.7)
		)
		(stroke
			(width 0)
			(type default)
		)
	)
	(wire
		(pts
			(xy 165.1 68.58) (xy 165.1 69.85)
		)
		(stroke
			(width 0)
			(type default)
		)
	)
	(bus
		(pts
			(xy 247.65 152.4) (xy 247.65 154.94)
		)
		(stroke
			(width 0)
			(type default)
		)
	)
	(bus
		(pts
			(xy 165.1 162.56) (xy 165.1 167.64)
		)
		(stroke
			(width 0)
			(type default)
		)
	)
	(bus
		(pts
			(xy 165.1 154.94) (xy 165.1 160.02)
		)
		(stroke
			(width 0)
			(type default)
		)
	)
	(bus
		(pts
			(xy 165.1 132.08) (xy 165.1 137.16)
		)
		(stroke
			(width 0)
			(type default)
		)
	)
	(wire
		(pts
			(xy 199.39 218.44) (xy 198.12 218.44)
		)
		(stroke
			(width 0)
			(type default)
		)
	)
	(bus
		(pts
			(xy 165.1 147.32) (xy 165.1 152.4)
		)
		(stroke
			(width 0)
			(type default)
		)
	)
	(bus
		(pts
			(xy 247.65 144.78) (xy 247.65 147.32)
		)
		(stroke
			(width 0)
			(type default)
		)
	)
	(bus
		(pts
			(xy 165.1 106.68) (xy 165.1 109.22)
		)
		(stroke
			(width 0)
			(type default)
		)
	)
	(wire
		(pts
			(xy 193.04 101.6) (xy 190.5 101.6)
		)
		(stroke
			(width 0)
			(type default)
		)
	)
	(bus
		(pts
			(xy 247.65 147.32) (xy 247.65 152.4)
		)
		(stroke
			(width 0)
			(type default)
		)
	)
	(bus
		(pts
			(xy 165.1 114.3) (xy 165.1 116.84)
		)
		(stroke
			(width 0)
			(type default)
		)
	)
	(bus
		(pts
			(xy 247.65 132.08) (xy 247.65 137.16)
		)
		(stroke
			(width 0)
			(type default)
		)
	)
	(bus
		(pts
			(xy 165.1 152.4) (xy 165.1 154.94)
		)
		(stroke
			(width 0)
			(type default)
		)
	)
	(wire
		(pts
			(xy 193.04 170.18) (xy 167.64 170.18)
		)
		(stroke
			(width 0)
			(type default)
		)
	)
	(bus
		(pts
			(xy 247.65 114.3) (xy 247.65 116.84)
		)
		(stroke
			(width 0)
			(type default)
		)
	)
	(wire
		(pts
			(xy 219.71 210.82) (xy 228.6 210.82)
		)
		(stroke
			(width 0)
			(type default)
		)
	)
	(wire
		(pts
			(xy 226.06 73.66) (xy 236.22 73.66)
		)
		(stroke
			(width 0)
			(type default)
		)
	)
	(wire
		(pts
			(xy 193.04 119.38) (xy 167.64 119.38)
		)
		(stroke
			(width 0)
			(type default)
		)
	)
	(wire
		(pts
			(xy 165.1 67.31) (xy 165.1 68.58)
		)
		(stroke
			(width 0)
			(type default)
		)
	)
	(bus
		(pts
			(xy 247.65 154.94) (xy 247.65 160.02)
		)
		(stroke
			(width 0)
			(type default)
		)
	)
	(wire
		(pts
			(xy 233.68 96.52) (xy 226.06 96.52)
		)
		(stroke
			(width 0)
			(type default)
		)
	)
	(bus
		(pts
			(xy 247.65 129.54) (xy 247.65 132.08)
		)
		(stroke
			(width 0)
			(type default)
		)
	)
	(wire
		(pts
			(xy 172.72 210.82) (xy 182.88 210.82)
		)
		(stroke
			(width 0)
			(type default)
		)
	)
	(bus
		(pts
			(xy 247.65 124.46) (xy 247.65 129.54)
		)
		(stroke
			(width 0)
			(type default)
		)
	)
	(wire
		(pts
			(xy 193.04 127) (xy 167.64 127)
		)
		(stroke
			(width 0)
			(type default)
		)
	)
	(bus
		(pts
			(xy 165.1 105.41) (xy 165.1 106.68)
		)
		(stroke
			(width 0)
			(type default)
		)
	)
	(wire
		(pts
			(xy 179.07 68.58) (xy 179.07 69.85)
		)
		(stroke
			(width 0)
			(type default)
		)
	)
	(wire
		(pts
			(xy 219.71 219.71) (xy 219.71 217.17)
		)
		(stroke
			(width 0)
			(type default)
		)
	)
	(wire
		(pts
			(xy 182.88 215.9) (xy 185.42 215.9)
		)
		(stroke
			(width 0)
			(type default)
		)
	)
	(bus
		(pts
			(xy 165.1 137.16) (xy 165.1 139.7)
		)
		(stroke
			(width 0)
			(type default)
		)
	)
	(wire
		(pts
			(xy 193.04 116.84) (xy 167.64 116.84)
		)
		(stroke
			(width 0)
			(type default)
		)
	)
	(bus
		(pts
			(xy 251.46 110.49) (xy 248.92 110.49)
		)
		(stroke
			(width 0)
			(type default)
		)
	)
	(wire
		(pts
			(xy 212.09 210.82) (xy 219.71 210.82)
		)
		(stroke
			(width 0)
			(type default)
		)
	)
	(wire
		(pts
			(xy 245.11 132.08) (xy 226.06 132.08)
		)
		(stroke
			(width 0)
			(type default)
		)
	)
	(bus
		(pts
			(xy 162.56 104.14) (xy 163.83 104.14)
		)
		(stroke
			(width 0)
			(type default)
		)
	)
	(bus
		(pts
			(xy 247.65 162.56) (xy 247.65 167.64)
		)
		(stroke
			(width 0)
			(type default)
		)
	)
	(wire
		(pts
			(xy 193.04 157.48) (xy 167.64 157.48)
		)
		(stroke
			(width 0)
			(type default)
		)
	)
	(wire
		(pts
			(xy 193.04 124.46) (xy 167.64 124.46)
		)
		(stroke
			(width 0)
			(type default)
		)
	)
	(wire
		(pts
			(xy 167.64 109.22) (xy 193.04 109.22)
		)
		(stroke
			(width 0)
			(type default)
		)
	)
	(bus
		(pts
			(xy 163.83 104.14) (xy 165.1 105.41)
		)
		(stroke
			(width 0)
			(type default)
		)
	)
	(wire
		(pts
			(xy 245.11 162.56) (xy 226.06 162.56)
		)
		(stroke
			(width 0)
			(type default)
		)
	)
	(wire
		(pts
			(xy 199.39 218.44) (xy 199.39 219.71)
		)
		(stroke
			(width 0)
			(type default)
		)
	)
	(bus
		(pts
			(xy 165.1 109.22) (xy 165.1 114.3)
		)
		(stroke
			(width 0)
			(type default)
		)
	)
	(wire
		(pts
			(xy 190.5 101.6) (xy 190.5 102.87)
		)
		(stroke
			(width 0)
			(type default)
		)
	)
	(wire
		(pts
			(xy 245.11 116.84) (xy 226.06 116.84)
		)
		(stroke
			(width 0)
			(type default)
		)
	)
	(wire
		(pts
			(xy 236.22 68.58) (xy 226.06 68.58)
		)
		(stroke
			(width 0)
			(type default)
		)
	)
	(bus
		(pts
			(xy 247.65 111.76) (xy 248.92 110.49)
		)
		(stroke
			(width 0)
			(type default)
		)
	)
	(wire
		(pts
			(xy 245.11 142.24) (xy 226.06 142.24)
		)
		(stroke
			(width 0)
			(type default)
		)
	)
	(wire
		(pts
			(xy 245.11 139.7) (xy 226.06 139.7)
		)
		(stroke
			(width 0)
			(type default)
		)
	)
	(wire
		(pts
			(xy 182.88 213.36) (xy 185.42 213.36)
		)
		(stroke
			(width 0)
			(type default)
		)
	)
	(wire
		(pts
			(xy 182.88 213.36) (xy 182.88 215.9)
		)
		(stroke
			(width 0)
			(type default)
		)
	)
	(wire
		(pts
			(xy 245.11 172.72) (xy 226.06 172.72)
		)
		(stroke
			(width 0)
			(type default)
		)
	)
	(wire
		(pts
			(xy 193.04 154.94) (xy 167.64 154.94)
		)
		(stroke
			(width 0)
			(type default)
		)
	)
	(bus
		(pts
			(xy 165.1 121.92) (xy 165.1 124.46)
		)
		(stroke
			(width 0)
			(type default)
		)
	)
	(bus
		(pts
			(xy 247.65 116.84) (xy 247.65 121.92)
		)
		(stroke
			(width 0)
			(type default)
		)
	)
	(wire
		(pts
			(xy 204.47 213.36) (xy 198.12 213.36)
		)
		(stroke
			(width 0)
			(type default)
		)
	)
	(wire
		(pts
			(xy 219.71 201.93) (xy 219.71 203.2)
		)
		(stroke
			(width 0)
			(type default)
		)
	)
	(wire
		(pts
			(xy 193.04 149.86) (xy 167.64 149.86)
		)
		(stroke
			(width 0)
			(type default)
		)
	)
	(bus
		(pts
			(xy 165.1 144.78) (xy 165.1 147.32)
		)
		(stroke
			(width 0)
			(type default)
		)
	)
	(wire
		(pts
			(xy 193.04 142.24) (xy 167.64 142.24)
		)
		(stroke
			(width 0)
			(type default)
		)
	)
	(bus
		(pts
			(xy 165.1 124.46) (xy 165.1 129.54)
		)
		(stroke
			(width 0)
			(type default)
		)
	)
	(bus
		(pts
			(xy 247.65 167.64) (xy 247.65 170.18)
		)
		(stroke
			(width 0)
			(type default)
		)
	)
	(wire
		(pts
			(xy 204.47 210.82) (xy 198.12 210.82)
		)
		(stroke
			(width 0)
			(type default)
		)
	)
	(bus
		(pts
			(xy 165.1 139.7) (xy 165.1 144.78)
		)
		(stroke
			(width 0)
			(type default)
		)
	)
	(wire
		(pts
			(xy 245.11 134.62) (xy 226.06 134.62)
		)
		(stroke
			(width 0)
			(type default)
		)
	)
	(wire
		(pts
			(xy 193.04 165.1) (xy 167.64 165.1)
		)
		(stroke
			(width 0)
			(type default)
		)
	)
	(wire
		(pts
			(xy 193.04 147.32) (xy 167.64 147.32)
		)
		(stroke
			(width 0)
			(type default)
		)
	)
	(bus
		(pts
			(xy 247.65 111.76) (xy 247.65 114.3)
		)
		(stroke
			(width 0)
			(type default)
		)
	)
	(bus
		(pts
			(xy 165.1 116.84) (xy 165.1 121.92)
		)
		(stroke
			(width 0)
			(type default)
		)
	)
	(wire
		(pts
			(xy 245.11 165.1) (xy 226.06 165.1)
		)
		(stroke
			(width 0)
			(type default)
		)
	)
	(wire
		(pts
			(xy 245.11 127) (xy 226.06 127)
		)
		(stroke
			(width 0)
			(type default)
		)
	)
	(wire
		(pts
			(xy 245.11 157.48) (xy 226.06 157.48)
		)
		(stroke
			(width 0)
			(type default)
		)
	)
	(wire
		(pts
			(xy 193.04 162.56) (xy 167.64 162.56)
		)
		(stroke
			(width 0)
			(type default)
		)
	)
	(wire
		(pts
			(xy 193.04 172.72) (xy 167.64 172.72)
		)
		(stroke
			(width 0)
			(type default)
		)
	)
	(label "x4"
		(at 204.47 213.36 180)
		(effects
			(font
				(size 1.27 1.27)
			)
			(justify right bottom)
		)
	)
	(label "x4"
		(at 236.22 73.66 180)
		(effects
			(font
				(size 1.27 1.27)
			)
			(justify right bottom)
		)
	)
	(label "PCIE.TXD2_P"
		(at 245.11 132.08 180)
		(effects
			(font
				(size 1.27 1.27)
			)
			(justify right bottom)
		)
	)
	(label "PCIE.TXD4_P"
		(at 245.11 147.32 180)
		(effects
			(font
				(size 1.27 1.27)
			)
			(justify right bottom)
		)
	)
	(label "PCIE.TXD6_N"
		(at 245.11 165.1 180)
		(effects
			(font
				(size 1.27 1.27)
			)
			(justify right bottom)
		)
	)
	(label "~{PERST}"
		(at 233.68 96.52 180)
		(effects
			(font
				(size 1.27 1.27)
			)
			(justify right bottom)
		)
	)
	(label "PRSNT#1"
		(at 172.72 210.82 0)
		(effects
			(font
				(size 1.27 1.27)
			)
			(justify left bottom)
		)
	)
	(label "PCIE.TXD5_P"
		(at 245.11 154.94 180)
		(effects
			(font
				(size 1.27 1.27)
			)
			(justify right bottom)
		)
	)
	(label "PCIE.RXD0_P"
		(at 167.64 116.84 0)
		(effects
			(font
				(size 1.27 1.27)
			)
			(justify left bottom)
		)
	)
	(label "PCIE.RXD7_P"
		(at 167.64 170.18 0)
		(effects
			(font
				(size 1.27 1.27)
			)
			(justify left bottom)
		)
	)
	(label "PCIE.RXD5_N"
		(at 167.64 157.48 0)
		(effects
			(font
				(size 1.27 1.27)
			)
			(justify left bottom)
		)
	)
	(label "PCIE.RXD0_N"
		(at 167.64 119.38 0)
		(effects
			(font
				(size 1.27 1.27)
			)
			(justify left bottom)
		)
	)
	(label "PCIE.TXD3_N"
		(at 245.11 142.24 180)
		(effects
			(font
				(size 1.27 1.27)
			)
			(justify right bottom)
		)
	)
	(label "PCIE.RXD7_N"
		(at 167.64 172.72 0)
		(effects
			(font
				(size 1.27 1.27)
			)
			(justify left bottom)
		)
	)
	(label "PCIE.TXD1_N"
		(at 245.11 127 180)
		(effects
			(font
				(size 1.27 1.27)
			)
			(justify right bottom)
		)
	)
	(label "PCIE.TXD5_N"
		(at 245.11 157.48 180)
		(effects
			(font
				(size 1.27 1.27)
			)
			(justify right bottom)
		)
	)
	(label "PCIE.RXD2_N"
		(at 167.64 134.62 0)
		(effects
			(font
				(size 1.27 1.27)
			)
			(justify left bottom)
		)
	)
	(label "PCIE.TXD0_P"
		(at 245.11 116.84 180)
		(effects
			(font
				(size 1.27 1.27)
			)
			(justify right bottom)
		)
	)
	(label "PCIE.TXD1_P"
		(at 245.11 124.46 180)
		(effects
			(font
				(size 1.27 1.27)
			)
			(justify right bottom)
		)
	)
	(label "x1"
		(at 236.22 71.12 180)
		(effects
			(font
				(size 1.27 1.27)
			)
			(justify right bottom)
		)
	)
	(label "PCIE.RXD3_P"
		(at 167.64 139.7 0)
		(effects
			(font
				(size 1.27 1.27)
			)
			(justify left bottom)
		)
	)
	(label "x1"
		(at 204.47 210.82 180)
		(effects
			(font
				(size 1.27 1.27)
			)
			(justify right bottom)
		)
	)
	(label "PCIE.RXD2_P"
		(at 167.64 132.08 0)
		(effects
			(font
				(size 1.27 1.27)
			)
			(justify left bottom)
		)
	)
	(label "PCIE.RXD6_N"
		(at 167.64 165.1 0)
		(effects
			(font
				(size 1.27 1.27)
			)
			(justify left bottom)
		)
	)
	(label "PCIE.TXD3_P"
		(at 245.11 139.7 180)
		(effects
			(font
				(size 1.27 1.27)
			)
			(justify right bottom)
		)
	)
	(label "PCIE.TXD2_N"
		(at 245.11 134.62 180)
		(effects
			(font
				(size 1.27 1.27)
			)
			(justify right bottom)
		)
	)
	(label "PCIE.RXD1_P"
		(at 167.64 124.46 0)
		(effects
			(font
				(size 1.27 1.27)
			)
			(justify left bottom)
		)
	)
	(label "PCIE.RXD4_P"
		(at 167.64 147.32 0)
		(effects
			(font
				(size 1.27 1.27)
			)
			(justify left bottom)
		)
	)
	(label "~{PERST}"
		(at 212.09 210.82 0)
		(effects
			(font
				(size 1.27 1.27)
			)
			(justify left bottom)
		)
	)
	(label "PCIE.TXD7_P"
		(at 245.11 170.18 180)
		(effects
			(font
				(size 1.27 1.27)
			)
			(justify right bottom)
		)
	)
	(label "PCIE.CLK_N"
		(at 167.64 111.76 0)
		(effects
			(font
				(size 1.27 1.27)
			)
			(justify left bottom)
		)
	)
	(label "PCIE.RXD3_N"
		(at 167.64 142.24 0)
		(effects
			(font
				(size 1.27 1.27)
			)
			(justify left bottom)
		)
	)
	(label "x8"
		(at 204.47 215.9 180)
		(effects
			(font
				(size 1.27 1.27)
			)
			(justify right bottom)
		)
	)
	(label "PCIE.RXD6_P"
		(at 167.64 162.56 0)
		(effects
			(font
				(size 1.27 1.27)
			)
			(justify left bottom)
		)
	)
	(label "PRSNT#1"
		(at 236.22 68.58 180)
		(effects
			(font
				(size 1.27 1.27)
			)
			(justify right bottom)
		)
	)
	(label "PCIE.RXD4_N"
		(at 167.64 149.86 0)
		(effects
			(font
				(size 1.27 1.27)
			)
			(justify left bottom)
		)
	)
	(label "PCIE.TXD6_P"
		(at 245.11 162.56 180)
		(effects
			(font
				(size 1.27 1.27)
			)
			(justify right bottom)
		)
	)
	(label "PCIE.RXD5_P"
		(at 167.64 154.94 0)
		(effects
			(font
				(size 1.27 1.27)
			)
			(justify left bottom)
		)
	)
	(label "PCIE.CLK_P"
		(at 167.64 109.22 0)
		(effects
			(font
				(size 1.27 1.27)
			)
			(justify left bottom)
		)
	)
	(label "PCIE.TXD7_N"
		(at 245.11 172.72 180)
		(effects
			(font
				(size 1.27 1.27)
			)
			(justify right bottom)
		)
	)
	(label "PCIE.TXD4_N"
		(at 245.11 149.86 180)
		(effects
			(font
				(size 1.27 1.27)
			)
			(justify right bottom)
		)
	)
	(label "x8"
		(at 236.22 76.2 180)
		(effects
			(font
				(size 1.27 1.27)
			)
			(justify right bottom)
		)
	)
	(label "PCIE.TXD0_N"
		(at 245.11 119.38 180)
		(effects
			(font
				(size 1.27 1.27)
			)
			(justify right bottom)
		)
	)
	(label "PCIE.RXD1_N"
		(at 167.64 127 0)
		(effects
			(font
				(size 1.27 1.27)
			)
			(justify left bottom)
		)
	)
	(global_label "PCIE.PWRGD"
		(shape input)
		(at 228.6 210.82 0)
		(fields_autoplaced yes)
		(effects
			(font
				(size 1.27 1.27)
			)
			(justify left)
		)
		(property "Intersheetrefs" "${INTERSHEET_REFS}"
			(at 242.3542 210.7406 0)
			(effects
				(font
					(size 1.27 1.27)
				)
				(justify left)
			)
		)
	)
	(hierarchical_label "PCIE{PCIe_x8}"
		(shape bidirectional)
		(at 251.46 110.49 0)
		(effects
			(font
				(size 1.27 1.27)
			)
			(justify left)
		)
	)
	(hierarchical_label "PCIE{PCIe_x8}"
		(shape bidirectional)
		(at 162.56 104.14 180)
		(effects
			(font
				(size 1.27 1.27)
			)
			(justify right)
		)
	)
	(symbol
		(lib_id "antmicropower:GND")
		(at 165.1 74.93 0)
		(unit 1)
		(exclude_from_sim no)
		(in_bom yes)
		(on_board yes)
		(dnp no)
		(property "Reference" "#PWR0398"
			(at 165.1 81.28 0)
			(effects
				(font
					(size 1.27 1.27)
				)
				(hide yes)
			)
		)
		(property "Value" "GND"
			(at 163.195 79.375 0)
			(effects
				(font
					(size 1.27 1.27)
					(thickness 0.15)
				)
				(justify left bottom)
			)
		)
		(property "Footprint" ""
			(at 173.99 82.55 0)
			(effects
				(font
					(size 1.27 1.27)
					(thickness 0.15)
				)
				(justify left bottom)
				(hide yes)
			)
		)
		(property "Datasheet" ""
			(at 173.99 87.63 0)
			(effects
				(font
					(size 1.27 1.27)
					(thickness 0.15)
				)
				(justify left bottom)
				(hide yes)
			)
		)
		(property "Description" ""
			(at 165.1 74.93 0)
			(effects
				(font
					(size 1.27 1.27)
				)
				(hide yes)
			)
		)
		(property "Author" "Antmicro"
			(at 173.99 80.01 0)
			(effects
				(font
					(size 1.27 1.27)
					(thickness 0.15)
				)
				(justify left bottom)
				(hide yes)
			)
		)
		(property "License" "Apache-2.0"
			(at 173.99 82.55 0)
			(effects
				(font
					(size 1.27 1.27)
					(thickness 0.15)
				)
				(justify left bottom)
				(hide yes)
			)
		)
		(pin "1"
		)
		(instances
			(project "data-center-rdimm-ddr5-tester"
				(path ""
					(reference "#PWR0398")
					(unit 1)
				)
			)
		)
	)
	(symbol
		(lib_id "antmicropower:GND")
		(at 190.5 102.87 0)
		(unit 1)
		(exclude_from_sim no)
		(in_bom yes)
		(on_board yes)
		(dnp no)
		(property "Reference" "#PWR0319"
			(at 190.5 109.22 0)
			(effects
				(font
					(size 1.27 1.27)
				)
				(hide yes)
			)
		)
		(property "Value" "GND"
			(at 188.595 107.315 0)
			(effects
				(font
					(size 1.27 1.27)
					(thickness 0.15)
				)
				(justify left bottom)
			)
		)
		(property "Footprint" ""
			(at 199.39 110.49 0)
			(effects
				(font
					(size 1.27 1.27)
					(thickness 0.15)
				)
				(justify left bottom)
				(hide yes)
			)
		)
		(property "Datasheet" ""
			(at 199.39 115.57 0)
			(effects
				(font
					(size 1.27 1.27)
					(thickness 0.15)
				)
				(justify left bottom)
				(hide yes)
			)
		)
		(property "Description" ""
			(at 190.5 102.87 0)
			(effects
				(font
					(size 1.27 1.27)
				)
				(hide yes)
			)
		)
		(property "Author" "Antmicro"
			(at 199.39 107.95 0)
			(effects
				(font
					(size 1.27 1.27)
					(thickness 0.15)
				)
				(justify left bottom)
				(hide yes)
			)
		)
		(property "License" "Apache-2.0"
			(at 199.39 110.49 0)
			(effects
				(font
					(size 1.27 1.27)
					(thickness 0.15)
				)
				(justify left bottom)
				(hide yes)
			)
		)
		(pin "1"
		)
		(instances
			(project "data-center-rdimm-ddr5-tester"
				(path ""
					(reference "#PWR0319")
					(unit 1)
				)
			)
		)
	)
	(symbol
		(lib_id "antmicroSlideSwitches:CVS-03B")
		(at 185.42 210.82 0)
		(unit 1)
		(exclude_from_sim no)
		(in_bom yes)
		(on_board yes)
		(dnp no)
		(fields_autoplaced yes)
		(property "Reference" "SW1"
			(at 191.77 203.2 0)
			(effects
				(font
					(size 1.27 1.27)
					(thickness 0.15)
				)
			)
		)
		(property "Value" "CVS-03B"
			(at 191.77 205.74 0)
			(effects
				(font
					(size 1.27 1.27)
					(thickness 0.15)
				)
				(hide yes)
			)
		)
		(property "Footprint" "antmicro-footprints:SW_DIP_SPSTx03_Slide_Copal_CVS-03xB_W5.9mm_P1mm"
			(at 212.09 218.44 0)
			(effects
				(font
					(size 1.27 1.27)
					(thickness 0.15)
				)
				(justify left bottom)
				(hide yes)
			)
		)
		(property "Datasheet" "https://www.mouser.com/datasheet/2/972/cvs-1827291.pdf"
			(at 212.09 220.98 0)
			(effects
				(font
					(size 1.27 1.27)
					(thickness 0.15)
				)
				(justify left bottom)
				(hide yes)
			)
		)
		(property "Description" ""
			(at 185.42 210.82 0)
			(effects
				(font
					(size 1.27 1.27)
				)
				(hide yes)
			)
		)
		(property "MPN" "CVS-03B"
			(at 191.77 205.74 0)
			(effects
				(font
					(size 1.27 1.27)
					(thickness 0.15)
				)
			)
		)
		(property "Manufacturer" "Nidec Components"
			(at 212.09 226.06 0)
			(effects
				(font
					(size 1.27 1.27)
					(thickness 0.15)
				)
				(justify left bottom)
				(hide yes)
			)
		)
		(property "Author" "Antmicro"
			(at 212.09 228.6 0)
			(effects
				(font
					(size 1.27 1.27)
					(thickness 0.15)
				)
				(justify left bottom)
				(hide yes)
			)
		)
		(property "License" "Apache-2.0"
			(at 212.09 231.14 0)
			(effects
				(font
					(size 1.27 1.27)
					(thickness 0.15)
				)
				(justify left bottom)
				(hide yes)
			)
		)
		(pin "1"
		)
		(pin "3"
		)
		(pin "5"
		)
		(pin "6"
		)
		(pin "7"
		)
		(pin "4"
		)
		(pin "2"
		)
		(instances
			(project "data-center-rdimm-ddr5-tester"
				(path ""
					(reference "SW1")
					(unit 1)
				)
			)
		)
	)
	(symbol
		(lib_id "antmicropower:+12V")
		(at 165.1 67.31 0)
		(unit 1)
		(exclude_from_sim no)
		(in_bom yes)
		(on_board yes)
		(dnp no)
		(fields_autoplaced yes)
		(property "Reference" "#PWR0422"
			(at 165.1 71.12 0)
			(effects
				(font
					(size 1.27 1.27)
				)
				(hide yes)
			)
		)
		(property "Value" "+12V"
			(at 165.1 63.7342 0)
			(effects
				(font
					(size 1.27 1.27)
				)
			)
		)
		(property "Footprint" ""
			(at 165.1 67.31 0)
			(effects
				(font
					(size 1.27 1.27)
				)
				(hide yes)
			)
		)
		(property "Datasheet" ""
			(at 165.1 67.31 0)
			(effects
				(font
					(size 1.27 1.27)
				)
				(hide yes)
			)
		)
		(property "Description" ""
			(at 165.1 67.31 0)
			(effects
				(font
					(size 1.27 1.27)
				)
				(hide yes)
			)
		)
		(pin "1"
		)
		(instances
			(project "data-center-rdimm-ddr5-tester"
				(path ""
					(reference "#PWR0422")
					(unit 1)
				)
			)
		)
	)
	(symbol
		(lib_id "antmicropower:GND")
		(at 219.71 219.71 0)
		(unit 1)
		(exclude_from_sim no)
		(in_bom yes)
		(on_board yes)
		(dnp no)
		(fields_autoplaced yes)
		(property "Reference" "#PWR0402"
			(at 219.71 226.06 0)
			(effects
				(font
					(size 1.27 1.27)
				)
				(hide yes)
			)
		)
		(property "Value" "GND"
			(at 217.805 224.155 0)
			(effects
				(font
					(size 1.27 1.27)
					(thickness 0.15)
				)
				(justify left bottom)
			)
		)
		(property "Footprint" ""
			(at 228.6 227.33 0)
			(effects
				(font
					(size 1.27 1.27)
					(thickness 0.15)
				)
				(justify left bottom)
				(hide yes)
			)
		)
		(property "Datasheet" ""
			(at 228.6 232.41 0)
			(effects
				(font
					(size 1.27 1.27)
					(thickness 0.15)
				)
				(justify left bottom)
				(hide yes)
			)
		)
		(property "Description" ""
			(at 219.71 219.71 0)
			(effects
				(font
					(size 1.27 1.27)
				)
				(hide yes)
			)
		)
		(property "Author" "Antmicro"
			(at 228.6 224.79 0)
			(effects
				(font
					(size 1.27 1.27)
					(thickness 0.15)
				)
				(justify left bottom)
				(hide yes)
			)
		)
		(property "License" "Apache-2.0"
			(at 228.6 227.33 0)
			(effects
				(font
					(size 1.27 1.27)
					(thickness 0.15)
				)
				(justify left bottom)
				(hide yes)
			)
		)
		(pin "1"
		)
		(instances
			(project "data-center-rdimm-ddr5-tester"
				(path ""
					(reference "#PWR0402")
					(unit 1)
				)
			)
		)
	)
	(symbol
		(lib_id "antmicropower:GND")
		(at 199.39 219.71 0)
		(mirror y)
		(unit 1)
		(exclude_from_sim no)
		(in_bom yes)
		(on_board yes)
		(dnp no)
		(fields_autoplaced yes)
		(property "Reference" "#PWR0403"
			(at 199.39 226.06 0)
			(effects
				(font
					(size 1.27 1.27)
				)
				(hide yes)
			)
		)
		(property "Value" "GND"
			(at 201.295 224.155 0)
			(effects
				(font
					(size 1.27 1.27)
					(thickness 0.15)
				)
				(justify left bottom)
			)
		)
		(property "Footprint" ""
			(at 190.5 227.33 0)
			(effects
				(font
					(size 1.27 1.27)
					(thickness 0.15)
				)
				(justify left bottom)
				(hide yes)
			)
		)
		(property "Datasheet" ""
			(at 190.5 232.41 0)
			(effects
				(font
					(size 1.27 1.27)
					(thickness 0.15)
				)
				(justify left bottom)
				(hide yes)
			)
		)
		(property "Description" ""
			(at 199.39 219.71 0)
			(effects
				(font
					(size 1.27 1.27)
				)
				(hide yes)
			)
		)
		(property "Author" "Antmicro"
			(at 190.5 224.79 0)
			(effects
				(font
					(size 1.27 1.27)
					(thickness 0.15)
				)
				(justify left bottom)
				(hide yes)
			)
		)
		(property "License" "Apache-2.0"
			(at 190.5 227.33 0)
			(effects
				(font
					(size 1.27 1.27)
					(thickness 0.15)
				)
				(justify left bottom)
				(hide yes)
			)
		)
		(pin "1"
		)
		(instances
			(project "data-center-rdimm-ddr5-tester"
				(path ""
					(reference "#PWR0403")
					(unit 1)
				)
			)
		)
	)
	(symbol
		(lib_id "antmicroCapacitors0603:C_10u_25V_0603")
		(at 179.07 74.93 90)
		(unit 1)
		(exclude_from_sim no)
		(in_bom yes)
		(on_board yes)
		(dnp no)
		(fields_autoplaced yes)
		(property "Reference" "C225"
			(at 181.61 71.1135 90)
			(effects
				(font
					(size 1.27 1.27)
					(thickness 0.15)
				)
				(justify right)
			)
		)
		(property "Value" "C_10u_25V_0603"
			(at 189.23 54.61 0)
			(effects
				(font
					(size 1.27 1.27)
					(thickness 0.15)
				)
				(justify left bottom)
				(hide yes)
			)
		)
		(property "Footprint" "antmicro-footprints:C_0603_1608Metric"
			(at 191.77 54.61 0)
			(effects
				(font
					(size 1.27 1.27)
					(thickness 0.15)
				)
				(justify left bottom)
				(hide yes)
			)
		)
		(property "Datasheet" "https://product.tdk.com/en/search/capacitor/ceramic/mlcc/info?part_no=C1608X5R1E106M080AC"
			(at 194.31 54.61 0)
			(effects
				(font
					(size 1.27 1.27)
					(thickness 0.15)
				)
				(justify left bottom)
				(hide yes)
			)
		)
		(property "Description" ""
			(at 179.07 74.93 0)
			(effects
				(font
					(size 1.27 1.27)
				)
				(hide yes)
			)
		)
		(property "MPN" "C1608X5R1E106M080AC"
			(at 196.85 54.61 0)
			(effects
				(font
					(size 1.27 1.27)
					(thickness 0.15)
				)
				(justify left bottom)
				(hide yes)
			)
		)
		(property "Manufacturer" "TDK"
			(at 199.39 54.61 0)
			(effects
				(font
					(size 1.27 1.27)
					(thickness 0.15)
				)
				(justify left bottom)
				(hide yes)
			)
		)
		(property "License" "Apache-2.0"
			(at 201.93 54.61 0)
			(effects
				(font
					(size 1.27 1.27)
					(thickness 0.15)
				)
				(justify left bottom)
				(hide yes)
			)
		)
		(property "Author" "Antmicro"
			(at 204.47 54.61 0)
			(effects
				(font
					(size 1.27 1.27)
					(thickness 0.15)
				)
				(justify left bottom)
				(hide yes)
			)
		)
		(property "Val" "10u"
			(at 181.61 73.6535 90)
			(effects
				(font
					(size 1.27 1.27)
					(thickness 0.15)
				)
				(justify right)
			)
		)
		(property "Voltage" "25V"
			(at 207.01 54.61 0)
			(effects
				(font
					(size 1.27 1.27)
				)
				(justify left bottom)
				(hide yes)
			)
		)
		(property "Dielectric" ""
			(at 209.55 54.61 0)
			(effects
				(font
					(size 1.27 1.27)
				)
				(justify left bottom)
				(hide yes)
			)
		)
		(pin "1"
		)
		(pin "2"
		)
		(instances
			(project "data-center-rdimm-ddr5-tester"
				(path ""
					(reference "C225")
					(unit 1)
				)
			)
		)
	)
	(symbol
		(lib_id "antmicroCapacitors0603:C_10u_25V_0603")
		(at 165.1 74.93 90)
		(unit 1)
		(exclude_from_sim no)
		(in_bom yes)
		(on_board yes)
		(dnp no)
		(fields_autoplaced yes)
		(property "Reference" "C224"
			(at 167.64 71.1135 90)
			(effects
				(font
					(size 1.27 1.27)
					(thickness 0.15)
				)
				(justify right)
			)
		)
		(property "Value" "C_10u_25V_0603"
			(at 175.26 54.61 0)
			(effects
				(font
					(size 1.27 1.27)
					(thickness 0.15)
				)
				(justify left bottom)
				(hide yes)
			)
		)
		(property "Footprint" "antmicro-footprints:C_0603_1608Metric"
			(at 177.8 54.61 0)
			(effects
				(font
					(size 1.27 1.27)
					(thickness 0.15)
				)
				(justify left bottom)
				(hide yes)
			)
		)
		(property "Datasheet" "https://product.tdk.com/en/search/capacitor/ceramic/mlcc/info?part_no=C1608X5R1E106M080AC"
			(at 180.34 54.61 0)
			(effects
				(font
					(size 1.27 1.27)
					(thickness 0.15)
				)
				(justify left bottom)
				(hide yes)
			)
		)
		(property "Description" ""
			(at 165.1 74.93 0)
			(effects
				(font
					(size 1.27 1.27)
				)
				(hide yes)
			)
		)
		(property "MPN" "C1608X5R1E106M080AC"
			(at 182.88 54.61 0)
			(effects
				(font
					(size 1.27 1.27)
					(thickness 0.15)
				)
				(justify left bottom)
				(hide yes)
			)
		)
		(property "Manufacturer" "TDK"
			(at 185.42 54.61 0)
			(effects
				(font
					(size 1.27 1.27)
					(thickness 0.15)
				)
				(justify left bottom)
				(hide yes)
			)
		)
		(property "License" "Apache-2.0"
			(at 187.96 54.61 0)
			(effects
				(font
					(size 1.27 1.27)
					(thickness 0.15)
				)
				(justify left bottom)
				(hide yes)
			)
		)
		(property "Author" "Antmicro"
			(at 190.5 54.61 0)
			(effects
				(font
					(size 1.27 1.27)
					(thickness 0.15)
				)
				(justify left bottom)
				(hide yes)
			)
		)
		(property "Val" "10u"
			(at 167.64 73.6535 90)
			(effects
				(font
					(size 1.27 1.27)
					(thickness 0.15)
				)
				(justify right)
			)
		)
		(property "Voltage" "25V"
			(at 193.04 54.61 0)
			(effects
				(font
					(size 1.27 1.27)
				)
				(justify left bottom)
				(hide yes)
			)
		)
		(property "Dielectric" ""
			(at 195.58 54.61 0)
			(effects
				(font
					(size 1.27 1.27)
				)
				(justify left bottom)
				(hide yes)
			)
		)
		(pin "1"
		)
		(pin "2"
		)
		(instances
			(project "data-center-rdimm-ddr5-tester"
				(path ""
					(reference "C224")
					(unit 1)
				)
			)
		)
	)
	(symbol
		(lib_id "antmicroEdgeConnectors:PCB-Edge_PCIexpress_x8")
		(at 193.04 68.58 0)
		(unit 1)
		(exclude_from_sim no)
		(in_bom no)
		(on_board yes)
		(dnp no)
		(fields_autoplaced yes)
		(property "Reference" "J10"
			(at 209.55 60.96 0)
			(effects
				(font
					(size 1.27 1.27)
					(thickness 0.15)
				)
			)
		)
		(property "Value" "PCB-Edge_PCIexpress_x8"
			(at 209.55 63.5 0)
			(effects
				(font
					(size 1.27 1.27)
					(thickness 0.15)
				)
			)
		)
		(property "Footprint" "antmicro-footprints:PCB-Edge_PCIexpress_x8"
			(at 241.3 78.74 0)
			(effects
				(font
					(size 1.27 1.27)
					(thickness 0.15)
				)
				(justify left bottom)
				(hide yes)
			)
		)
		(property "Datasheet" ""
			(at 241.3 81.28 0)
			(effects
				(font
					(size 1.27 1.27)
					(thickness 0.15)
				)
				(justify left bottom)
				(hide yes)
			)
		)
		(property "Description" ""
			(at 193.04 68.58 0)
			(effects
				(font
					(size 1.27 1.27)
				)
				(hide yes)
			)
		)
		(property "Author" "Antmicro"
			(at 241.3 81.28 0)
			(effects
				(font
					(size 1.27 1.27)
					(thickness 0.15)
				)
				(justify left bottom)
				(hide yes)
			)
		)
		(property "License" "Apache-2.0"
			(at 241.3 83.82 0)
			(effects
				(font
					(size 1.27 1.27)
					(thickness 0.15)
				)
				(justify left bottom)
				(hide yes)
			)
		)
		(pin "B24"
		)
		(pin "B23"
		)
		(pin "A38"
		)
		(pin "B17"
		)
		(pin "A11"
		)
		(pin "A43"
		)
		(pin "A42"
		)
		(pin "B22"
		)
		(pin "B7"
		)
		(pin "B6"
		)
		(pin "A21"
		)
		(pin "A4"
		)
		(pin "A23"
		)
		(pin "A39"
		)
		(pin "B18"
		)
		(pin "B16"
		)
		(pin "B33"
		)
		(pin "A22"
		)
		(pin "A8"
		)
		(pin "B48"
		)
		(pin "B46"
		)
		(pin "B49"
		)
		(pin "A24"
		)
		(pin "B32"
		)
		(pin "A1"
		)
		(pin "B4"
		)
		(pin "A32"
		)
		(pin "B12"
		)
		(pin "B14"
		)
		(pin "B47"
		)
		(pin "A13"
		)
		(pin "A44"
		)
		(pin "B35"
		)
		(pin "A29"
		)
		(pin "B36"
		)
		(pin "B44"
		)
		(pin "A20"
		)
		(pin "A48"
		)
		(pin "A40"
		)
		(pin "A2"
		)
		(pin "A28"
		)
		(pin "B1"
		)
		(pin "A27"
		)
		(pin "B26"
		)
		(pin "A15"
		)
		(pin "B5"
		)
		(pin "A49"
		)
		(pin "B13"
		)
		(pin "A9"
		)
		(pin "A26"
		)
		(pin "A35"
		)
		(pin "B31"
		)
		(pin "A45"
		)
		(pin "A46"
		)
		(pin "B15"
		)
		(pin "B19"
		)
		(pin "A33"
		)
		(pin "B41"
		)
		(pin "B42"
		)
		(pin "A6"
		)
		(pin "A37"
		)
		(pin "B2"
		)
		(pin "B28"
		)
		(pin "B38"
		)
		(pin "B45"
		)
		(pin "B20"
		)
		(pin "B30"
		)
		(pin "B11"
		)
		(pin "B29"
		)
		(pin "A31"
		)
		(pin "B3"
		)
		(pin "A30"
		)
		(pin "A47"
		)
		(pin "B39"
		)
		(pin "A36"
		)
		(pin "A16"
		)
		(pin "B10"
		)
		(pin "B37"
		)
		(pin "A19"
		)
		(pin "A34"
		)
		(pin "A25"
		)
		(pin "A7"
		)
		(pin "A12"
		)
		(pin "A41"
		)
		(pin "B34"
		)
		(pin "A14"
		)
		(pin "B25"
		)
		(pin "B21"
		)
		(pin "A18"
		)
		(pin "B8"
		)
		(pin "B40"
		)
		(pin "B43"
		)
		(pin "B9"
		)
		(pin "A5"
		)
		(pin "A3"
		)
		(pin "B27"
		)
		(pin "A17"
		)
		(pin "A10"
		)
		(instances
			(project "data-center-rdimm-ddr5-tester"
				(path ""
					(reference "J10")
					(unit 1)
				)
			)
		)
	)
	(symbol
		(lib_id "antmicropower:+3V3")
		(at 219.71 201.93 0)
		(unit 1)
		(exclude_from_sim no)
		(in_bom yes)
		(on_board yes)
		(dnp no)
		(fields_autoplaced yes)
		(property "Reference" "#PWR0401"
			(at 234.95 204.47 0)
			(effects
				(font
					(size 1.27 1.27)
					(thickness 0.15)
				)
				(justify left bottom)
				(hide yes)
			)
		)
		(property "Value" "+3V3"
			(at 216.535 199.39 0)
			(effects
				(font
					(size 1.27 1.27)
					(thickness 0.15)
				)
				(justify left bottom)
			)
		)
		(property "Footprint" ""
			(at 234.95 209.55 0)
			(effects
				(font
					(size 1.27 1.27)
					(thickness 0.15)
				)
				(justify left bottom)
				(hide yes)
			)
		)
		(property "Datasheet" ""
			(at 234.95 212.09 0)
			(effects
				(font
					(size 1.27 1.27)
					(thickness 0.15)
				)
				(justify left bottom)
				(hide yes)
			)
		)
		(property "Description" ""
			(at 219.71 201.93 0)
			(effects
				(font
					(size 1.27 1.27)
				)
				(hide yes)
			)
		)
		(property "Author" "Antmicro"
			(at 234.95 204.47 0)
			(effects
				(font
					(size 1.27 1.27)
					(thickness 0.15)
				)
				(justify left bottom)
				(hide yes)
			)
		)
		(property "License" "Apache-2.0"
			(at 234.95 207.01 0)
			(effects
				(font
					(size 1.27 1.27)
					(thickness 0.15)
				)
				(justify left bottom)
				(hide yes)
			)
		)
		(pin "1"
		)
		(instances
			(project "data-center-rdimm-ddr5-tester"
				(path ""
					(reference "#PWR0401")
					(unit 1)
				)
			)
		)
	)
	(symbol
		(lib_id "antmicropower:GND")
		(at 179.07 74.93 0)
		(unit 1)
		(exclude_from_sim no)
		(in_bom yes)
		(on_board yes)
		(dnp no)
		(property "Reference" "#PWR0399"
			(at 179.07 81.28 0)
			(effects
				(font
					(size 1.27 1.27)
				)
				(hide yes)
			)
		)
		(property "Value" "GND"
			(at 177.165 79.375 0)
			(effects
				(font
					(size 1.27 1.27)
					(thickness 0.15)
				)
				(justify left bottom)
			)
		)
		(property "Footprint" ""
			(at 187.96 82.55 0)
			(effects
				(font
					(size 1.27 1.27)
					(thickness 0.15)
				)
				(justify left bottom)
				(hide yes)
			)
		)
		(property "Datasheet" ""
			(at 187.96 87.63 0)
			(effects
				(font
					(size 1.27 1.27)
					(thickness 0.15)
				)
				(justify left bottom)
				(hide yes)
			)
		)
		(property "Description" ""
			(at 179.07 74.93 0)
			(effects
				(font
					(size 1.27 1.27)
				)
				(hide yes)
			)
		)
		(property "Author" "Antmicro"
			(at 187.96 80.01 0)
			(effects
				(font
					(size 1.27 1.27)
					(thickness 0.15)
				)
				(justify left bottom)
				(hide yes)
			)
		)
		(property "License" "Apache-2.0"
			(at 187.96 82.55 0)
			(effects
				(font
					(size 1.27 1.27)
					(thickness 0.15)
				)
				(justify left bottom)
				(hide yes)
			)
		)
		(pin "1"
		)
		(instances
			(project "data-center-rdimm-ddr5-tester"
				(path ""
					(reference "#PWR0399")
					(unit 1)
				)
			)
		)
	)
	(symbol
		(lib_id "antmicroResistors0402:R_10k_0402")
		(at 219.71 208.28 90)
		(unit 1)
		(exclude_from_sim no)
		(in_bom no)
		(on_board yes)
		(dnp yes)
		(fields_autoplaced yes)
		(property "Reference" "R191"
			(at 221.361 203.6435 90)
			(effects
				(font
					(size 1.27 1.27)
					(thickness 0.15)
				)
				(justify right)
			)
		)
		(property "Value" "R_10k_0402"
			(at 232.41 187.96 0)
			(effects
				(font
					(size 1.27 1.27)
					(thickness 0.15)
				)
				(justify left bottom)
				(hide yes)
			)
		)
		(property "Footprint" "antmicro-footprints:R_0402_1005Metric"
			(at 234.95 187.96 0)
			(effects
				(font
					(size 1.27 1.27)
					(thickness 0.15)
				)
				(justify left bottom)
				(hide yes)
			)
		)
		(property "Datasheet" "https://www.bourns.com/docs/product-datasheets/cr.pdf"
			(at 237.49 187.96 0)
			(effects
				(font
					(size 1.27 1.27)
					(thickness 0.15)
				)
				(justify left bottom)
				(hide yes)
			)
		)
		(property "Description" ""
			(at 219.71 208.28 0)
			(effects
				(font
					(size 1.27 1.27)
				)
				(hide yes)
			)
		)
		(property "MPN" "CR0402-FX-1002GLF"
			(at 240.03 187.96 0)
			(effects
				(font
					(size 1.27 1.27)
					(thickness 0.15)
				)
				(justify left bottom)
				(hide yes)
			)
		)
		(property "Manufacturer" "Bourns"
			(at 242.57 187.96 0)
			(effects
				(font
					(size 1.27 1.27)
					(thickness 0.15)
				)
				(justify left bottom)
				(hide yes)
			)
		)
		(property "License" "Apache-2.0"
			(at 245.11 187.96 0)
			(effects
				(font
					(size 1.27 1.27)
					(thickness 0.15)
				)
				(justify left bottom)
				(hide yes)
			)
		)
		(property "Author" "Antmicro"
			(at 247.65 187.96 0)
			(effects
				(font
					(size 1.27 1.27)
					(thickness 0.15)
				)
				(justify left bottom)
				(hide yes)
			)
		)
		(property "Val" "10k"
			(at 221.361 206.1672 90)
			(effects
				(font
					(size 1.27 1.27)
					(thickness 0.15)
				)
				(justify right)
			)
		)
		(property "Tolerance" "1%"
			(at 229.87 187.96 0)
			(effects
				(font
					(size 1.27 1.27)
				)
				(justify left bottom)
				(hide yes)
			)
		)
		(pin "1"
		)
		(pin "2"
		)
		(instances
			(project "data-center-rdimm-ddr5-tester"
				(path ""
					(reference "R191")
					(unit 1)
				)
			)
		)
	)
	(symbol
		(lib_id "antmicroResistors0402:R_10k_0402")
		(at 219.71 217.17 90)
		(unit 1)
		(exclude_from_sim no)
		(in_bom no)
		(on_board yes)
		(dnp yes)
		(fields_autoplaced yes)
		(property "Reference" "R192"
			(at 221.361 212.5335 90)
			(effects
				(font
					(size 1.27 1.27)
					(thickness 0.15)
				)
				(justify right)
			)
		)
		(property "Value" "R_10k_0402"
			(at 232.41 196.85 0)
			(effects
				(font
					(size 1.27 1.27)
					(thickness 0.15)
				)
				(justify left bottom)
				(hide yes)
			)
		)
		(property "Footprint" "antmicro-footprints:R_0402_1005Metric"
			(at 234.95 196.85 0)
			(effects
				(font
					(size 1.27 1.27)
					(thickness 0.15)
				)
				(justify left bottom)
				(hide yes)
			)
		)
		(property "Datasheet" "https://www.bourns.com/docs/product-datasheets/cr.pdf"
			(at 237.49 196.85 0)
			(effects
				(font
					(size 1.27 1.27)
					(thickness 0.15)
				)
				(justify left bottom)
				(hide yes)
			)
		)
		(property "Description" ""
			(at 219.71 217.17 0)
			(effects
				(font
					(size 1.27 1.27)
				)
				(hide yes)
			)
		)
		(property "MPN" "CR0402-FX-1002GLF"
			(at 240.03 196.85 0)
			(effects
				(font
					(size 1.27 1.27)
					(thickness 0.15)
				)
				(justify left bottom)
				(hide yes)
			)
		)
		(property "Manufacturer" "Bourns"
			(at 242.57 196.85 0)
			(effects
				(font
					(size 1.27 1.27)
					(thickness 0.15)
				)
				(justify left bottom)
				(hide yes)
			)
		)
		(property "License" "Apache-2.0"
			(at 245.11 196.85 0)
			(effects
				(font
					(size 1.27 1.27)
					(thickness 0.15)
				)
				(justify left bottom)
				(hide yes)
			)
		)
		(property "Author" "Antmicro"
			(at 247.65 196.85 0)
			(effects
				(font
					(size 1.27 1.27)
					(thickness 0.15)
				)
				(justify left bottom)
				(hide yes)
			)
		)
		(property "Val" "10k"
			(at 221.361 215.0572 90)
			(effects
				(font
					(size 1.27 1.27)
					(thickness 0.15)
				)
				(justify right)
			)
		)
		(property "Tolerance" "1%"
			(at 229.87 196.85 0)
			(effects
				(font
					(size 1.27 1.27)
				)
				(justify left bottom)
				(hide yes)
			)
		)
		(pin "1"
		)
		(pin "2"
		)
		(instances
			(project "data-center-rdimm-ddr5-tester"
				(path ""
					(reference "R192")
					(unit 1)
				)
			)
		)
	)
)
